# S9S_MB_2U (Grand Teton) — schematic netlist excerpt (pin names and nets, part order shuffled) for the footprints in the layout excerpt that follows; sources: Cadence DE-HDL packaged netlist, KiCad conversion of 03242023_DA0F0TMBIJ0_F0T_Motherboard_J_brd_V01_OCP.brd

PC503_P1_6  Q_CAP  2.2UF 10V 10% X6S  pkg C0402  page 287 : A = PVCCIN_CPU1_PVCC ; B = GND
PC1174_P0_4  Q_CAP  3300PF 50V 10% X7R  pkg 0402  page 272 : A = SW_P12V_PVCCFA_EHV_FIVRA_CPU0_L ; B = GND

(kicad_pcb
	(version 20260206)
	(generator "pcbnew")
	(generator_version "10.0")
	(general
		(thickness 1.6)
		(legacy_teardrops no)
	)
	(paper "A4")
	(title_block
		(title "03242023_DA0F0TMBIJ0_F0T_Motherboard_J_brd_V01_OCP.brd")
		(comment 1 "Grand Teton / footprints 248-249 of 6105")
	)
	(layers
		(0 "F.Cu" signal "TOP")
		(4 "In1.Cu" signal "GND")
		(6 "In2.Cu" signal "IN1")
		(8 "In3.Cu" signal "GND1")
		(10 "In4.Cu" signal "IN2")
		(12 "In5.Cu" signal "GND2")
		(14 "In6.Cu" signal "IN3")
		(16 "In7.Cu" signal "GND3")
		(18 "In8.Cu" signal "VCC")
		(20 "In9.Cu" signal "VCC1")
		(22 "In10.Cu" signal "GND4")
		(24 "In11.Cu" signal "IN4")
		(26 "In12.Cu" signal "GND5")
		(28 "In13.Cu" signal "IN5")
		(30 "In14.Cu" signal "GND6")
		(32 "In15.Cu" signal "IN6")
		(34 "In16.Cu" signal "GND7")
		(2 "B.Cu" signal "BOTTOM")
		(9 "F.Adhes" user "F.Adhesive")
		(11 "B.Adhes" user "B.Adhesive")
		(13 "F.Paste" user "Package Geometry/Pastemask Top")
		(15 "B.Paste" user "Package Geometry/Pastemask Bottom")
		(5 "F.SilkS" user "Ref Des/Silkscreen Top")
		(7 "B.SilkS" user "Ref Des/Silkscreen Bottom")
		(1 "F.Mask" user "Board Geometry/Soldermask Top")
		(3 "B.Mask" user "Board Geometry/Soldermask Bottom")
		(17 "Dwgs.User" user "User.Drawings")
		(19 "Cmts.User" user "User.Comments")
		(21 "Eco1.User" user "User.Eco1")
		(23 "Eco2.User" user "User.Eco2")
		(25 "Edge.Cuts" user "Board Geometry/Outline")
		(27 "Margin" user)
		(31 "F.CrtYd" user "Package Geometry/Place Bound Top")
		(29 "B.CrtYd" user "Package Geometry/Place Bound Bottom")
		(35 "F.Fab" user "Ref Des/Assembly Top")
		(33 "B.Fab" user "Ref Des/Assembly Bottom")
	)
	(footprint ""
		(layer "F.Cu")
		(at 85.262466 -336.935572 -90)
		(property "Reference" "PC503_P1_6"
			(at 0 0 270)
			(layer "F.SilkS")
			(hide yes)
			(effects
				(font
					(size 1.27 1.27)
				)
			)
		)
		(property "Value" ""
			(at 0 0 270)
			(layer "F.Fab")
			(effects
				(font
					(size 1.27 1.27)
				)
			)
		)
		(duplicate_pad_numbers_are_jumpers no)
		(fp_line
			(start -0.7874 0.4064)
			(end -0.7874 -0.4064)
			(stroke
				(width 0.1524)
				(type default)
			)
			(layer "F.SilkS")
		)
		(fp_line
			(start 0.7874 0.4064)
			(end -0.7874 0.4064)
			(stroke
				(width 0.1524)
				(type default)
			)
			(layer "F.SilkS")
		)
		(fp_line
			(start -0.7874 -0.4064)
			(end 0.7874 -0.4064)
			(stroke
				(width 0.1524)
				(type default)
			)
			(layer "F.SilkS")
		)
		(fp_line
			(start 0.7874 -0.4064)
			(end 0.7874 0.4064)
			(stroke
				(width 0.1524)
				(type default)
			)
			(layer "F.SilkS")
		)
		(fp_line
			(start -0.67945 0.3048)
			(end -0.67945 -0.305054)
			(stroke
				(width 0.1)
				(type default)
			)
			(layer "F.Fab")
		)
		(fp_line
			(start -0.12065 0.3048)
			(end -0.67945 0.3048)
			(stroke
				(width 0.1)
				(type default)
			)
			(layer "F.Fab")
		)
		(fp_line
			(start 0.120396 0.3048)
			(end 0.120396 0.2794)
			(stroke
				(width 0.1)
				(type default)
			)
			(layer "F.Fab")
		)
		(fp_line
			(start 0.67945 0.3048)
			(end 0.120396 0.3048)
			(stroke
				(width 0.1)
				(type default)
			)
			(layer "F.Fab")
		)
		(fp_line
			(start -0.12065 0.2794)
			(end -0.12065 0.3048)
			(stroke
				(width 0.1)
				(type default)
			)
			(layer "F.Fab")
		)
		(fp_line
			(start 0.120396 0.2794)
			(end -0.12065 0.2794)
			(stroke
				(width 0.1)
				(type default)
			)
			(layer "F.Fab")
		)
		(fp_line
			(start -0.12065 -0.2794)
			(end 0.12065 -0.2794)
			(stroke
				(width 0.1)
				(type default)
			)
			(layer "F.Fab")
		)
		(fp_line
			(start 0.12065 -0.2794)
			(end 0.12065 -0.3048)
			(stroke
				(width 0.1)
				(type default)
			)
			(layer "F.Fab")
		)
		(fp_line
			(start 0.12065 -0.3048)
			(end 0.67945 -0.3048)
			(stroke
				(width 0.1)
				(type default)
			)
			(layer "F.Fab")
		)
		(fp_line
			(start 0.67945 -0.3048)
			(end 0.67945 0.3048)
			(stroke
				(width 0.1)
				(type default)
			)
			(layer "F.Fab")
		)
		(fp_line
			(start -0.67945 -0.305054)
			(end -0.12065 -0.305054)
			(stroke
				(width 0.1)
				(type default)
			)
			(layer "F.Fab")
		)
		(fp_line
			(start -0.12065 -0.305054)
			(end -0.12065 -0.2794)
			(stroke
				(width 0.1)
				(type default)
			)
			(layer "F.Fab")
		)
		(pad "1" smd circle
			(at -0.40005 0 270)
			(size 0 0)
			(layers "F.Cu" "F.Mask" "F.Paste")
			(net "PVCCIN_CPU1_PVCC")
		)
		(pad "2" smd circle
			(at 0.40005 0 270)
			(size 0 0)
			(layers "F.Cu" "F.Mask" "F.Paste")
			(net "GND")
		)
	)
	(footprint ""
		(layer "F.Cu")
		(at 293.399718 -362.843826 -90)
		(property "Reference" "PC1174_P0_4"
			(at 0 0 270)
			(layer "F.SilkS")
			(hide yes)
			(effects
				(font
					(size 1.27 1.27)
				)
			)
		)
		(property "Value" ""
			(at 0 0 270)
			(layer "F.Fab")
			(effects
				(font
					(size 1.27 1.27)
				)
			)
		)
		(duplicate_pad_numbers_are_jumpers no)
		(fp_line
			(start -0.7874 0.4064)
			(end -0.7874 -0.4064)
			(stroke
				(width 0.1524)
				(type default)
			)
			(layer "F.SilkS")
		)
		(fp_line
			(start 0.7874 0.4064)
			(end -0.7874 0.4064)
			(stroke
				(width 0.1524)
				(type default)
			)
			(layer "F.SilkS")
		)
		(fp_line
			(start -0.7874 -0.4064)
			(end 0.7874 -0.4064)
			(stroke
				(width 0.1524)
				(type default)
			)
			(layer "F.SilkS")
		)
		(fp_line
			(start 0.7874 -0.4064)
			(end 0.7874 0.4064)
			(stroke
				(width 0.1524)
				(type default)
			)
			(layer "F.SilkS")
		)
		(fp_line
			(start -0.67945 0.3048)
			(end -0.67945 -0.305054)
			(stroke
				(width 0.1)
				(type default)
			)
			(layer "F.Fab")
		)
		(fp_line
			(start -0.12065 0.3048)
			(end -0.67945 0.3048)
			(stroke
				(width 0.1)
				(type default)
			)
			(layer "F.Fab")
		)
		(fp_line
			(start 0.120396 0.3048)
			(end 0.120396 0.2794)
			(stroke
				(width 0.1)
				(type default)
			)
			(layer "F.Fab")
		)
		(fp_line
			(start 0.67945 0.3048)
			(end 0.120396 0.3048)
			(stroke
				(width 0.1)
				(type default)
			)
			(layer "F.Fab")
		)
		(fp_line
			(start -0.12065 0.2794)
			(end -0.12065 0.3048)
			(stroke
				(width 0.1)
				(type default)
			)
			(layer "F.Fab")
		)
		(fp_line
			(start 0.120396 0.2794)
			(end -0.12065 0.2794)
			(stroke
				(width 0.1)
				(type default)
			)
			(layer "F.Fab")
		)
		(fp_line
			(start -0.12065 -0.2794)
			(end 0.12065 -0.2794)
			(stroke
				(width 0.1)
				(type default)
			)
			(layer "F.Fab")
		)
		(fp_line
			(start 0.12065 -0.2794)
			(end 0.12065 -0.3048)
			(stroke
				(width 0.1)
				(type default)
			)
			(layer "F.Fab")
		)
		(fp_line
			(start 0.12065 -0.3048)
			(end 0.67945 -0.3048)
			(stroke
				(width 0.1)
				(type default)
			)
			(layer "F.Fab")
		)
		(fp_line
			(start 0.67945 -0.3048)
			(end 0.67945 0.3048)
			(stroke
				(width 0.1)
				(type default)
			)
			(layer "F.Fab")
		)
		(fp_line
			(start -0.67945 -0.305054)
			(end -0.12065 -0.305054)
			(stroke
				(width 0.1)
				(type default)
			)
			(layer "F.Fab")
		)
		(fp_line
			(start -0.12065 -0.305054)
			(end -0.12065 -0.2794)
			(stroke
				(width 0.1)
				(type default)
			)
			(layer "F.Fab")
		)
		(pad "1" smd circle
			(at -0.40005 0 270)
			(size 0 0)
			(layers "F.Cu" "F.Mask" "F.Paste")
			(net "SW_P12V_PVCCFA_EHV_FIVRA_CPU0_L")
		)
		(pad "2" smd circle
			(at 0.40005 0 270)
			(size 0 0)
			(layers "F.Cu" "F.Mask" "F.Paste")
			(net "GND")
		)
	)
)
